# S9S_MB_2U (Grand Teton) — schematic netlist excerpt (pin names and nets, part order shuffled) for the footprints in the layout excerpt that follows; sources: Cadence DE-HDL packaged netlist, KiCad conversion of 03242023_DA0F0TMBIJ0_F0T_Motherboard_J_brd_V01_OCP.brd

H47  HOLE  EMPTY  pkg TH  page 311 : \1\ = GND
R762  Q_RES  0 5% CHIP  pkg 0402LF  page 131 : A = JTAG_DBP_CPU_GTL_TCK ; B = JTAG_DBP_CPU_GTL_TCK_R
R1702  Q_RES  4.7K 5% CHIP  pkg 0402LF  page 194 : A = P1V8_PCH_AUX ; B = SMB_M2_P0_1V8AUX_SDA_R

(kicad_pcb
	(version 20260206)
	(generator "pcbnew")
	(generator_version "10.0")
	(general
		(thickness 1.6)
		(legacy_teardrops no)
	)
	(paper "A4")
	(title_block
		(title "03242023_DA0F0TMBIJ0_F0T_Motherboard_J_brd_V01_OCP.brd")
		(comment 1 "Grand Teton / footprints 435-437 of 6105")
	)
	(layers
		(0 "F.Cu" signal "TOP")
		(4 "In1.Cu" signal "GND")
		(6 "In2.Cu" signal "IN1")
		(8 "In3.Cu" signal "GND1")
		(10 "In4.Cu" signal "IN2")
		(12 "In5.Cu" signal "GND2")
		(14 "In6.Cu" signal "IN3")
		(16 "In7.Cu" signal "GND3")
		(18 "In8.Cu" signal "VCC")
		(20 "In9.Cu" signal "VCC1")
		(22 "In10.Cu" signal "GND4")
		(24 "In11.Cu" signal "IN4")
		(26 "In12.Cu" signal "GND5")
		(28 "In13.Cu" signal "IN5")
		(30 "In14.Cu" signal "GND6")
		(32 "In15.Cu" signal "IN6")
		(34 "In16.Cu" signal "GND7")
		(2 "B.Cu" signal "BOTTOM")
		(9 "F.Adhes" user "F.Adhesive")
		(11 "B.Adhes" user "B.Adhesive")
		(13 "F.Paste" user "Package Geometry/Pastemask Top")
		(15 "B.Paste" user "Package Geometry/Pastemask Bottom")
		(5 "F.SilkS" user "Ref Des/Silkscreen Top")
		(7 "B.SilkS" user "Ref Des/Silkscreen Bottom")
		(1 "F.Mask" user "Board Geometry/Soldermask Top")
		(3 "B.Mask" user "Board Geometry/Soldermask Bottom")
		(17 "Dwgs.User" user "User.Drawings")
		(19 "Cmts.User" user "User.Comments")
		(21 "Eco1.User" user "User.Eco1")
		(23 "Eco2.User" user "User.Eco2")
		(25 "Edge.Cuts" user "Board Geometry/Outline")
		(27 "Margin" user)
		(31 "F.CrtYd" user "Package Geometry/Place Bound Top")
		(29 "B.CrtYd" user "Package Geometry/Place Bound Bottom")
		(35 "F.Fab" user "Ref Des/Assembly Top")
		(33 "B.Fab" user "Ref Des/Assembly Bottom")
	)
	(footprint ""
		(layer "F.Cu")
		(at 148.13788 -56.225948)
		(property "Reference" "R1702"
			(at 0 0 0)
			(layer "F.SilkS")
			(hide yes)
			(effects
				(font
					(size 1.27 1.27)
				)
			)
		)
		(property "Value" ""
			(at 0 0 0)
			(layer "F.Fab")
			(effects
				(font
					(size 1.27 1.27)
				)
			)
		)
		(duplicate_pad_numbers_are_jumpers no)
		(fp_line
			(start -0.7874 -0.4064)
			(end 0.7874 -0.4064)
			(stroke
				(width 0.1524)
				(type default)
			)
			(layer "F.SilkS")
		)
		(fp_line
			(start -0.7874 0.4064)
			(end -0.7874 -0.4064)
			(stroke
				(width 0.1524)
				(type default)
			)
			(layer "F.SilkS")
		)
		(fp_line
			(start 0.7874 -0.4064)
			(end 0.7874 0.4064)
			(stroke
				(width 0.1524)
				(type default)
			)
			(layer "F.SilkS")
		)
		(fp_line
			(start 0.7874 0.4064)
			(end -0.7874 0.4064)
			(stroke
				(width 0.1524)
				(type default)
			)
			(layer "F.SilkS")
		)
		(fp_line
			(start -0.67945 -0.305054)
			(end -0.12065 -0.305054)
			(stroke
				(width 0.1)
				(type default)
			)
			(layer "F.Fab")
		)
		(fp_line
			(start -0.67945 0.3048)
			(end -0.67945 -0.305054)
			(stroke
				(width 0.1)
				(type default)
			)
			(layer "F.Fab")
		)
		(fp_line
			(start -0.12065 -0.305054)
			(end -0.12065 -0.2794)
			(stroke
				(width 0.1)
				(type default)
			)
			(layer "F.Fab")
		)
		(fp_line
			(start -0.12065 -0.2794)
			(end 0.12065 -0.2794)
			(stroke
				(width 0.1)
				(type default)
			)
			(layer "F.Fab")
		)
		(fp_line
			(start -0.12065 0.2794)
			(end -0.12065 0.3048)
			(stroke
				(width 0.1)
				(type default)
			)
			(layer "F.Fab")
		)
		(fp_line
			(start -0.12065 0.3048)
			(end -0.67945 0.3048)
			(stroke
				(width 0.1)
				(type default)
			)
			(layer "F.Fab")
		)
		(fp_line
			(start 0.120396 0.2794)
			(end -0.12065 0.2794)
			(stroke
				(width 0.1)
				(type default)
			)
			(layer "F.Fab")
		)
		(fp_line
			(start 0.120396 0.3048)
			(end 0.120396 0.2794)
			(stroke
				(width 0.1)
				(type default)
			)
			(layer "F.Fab")
		)
		(fp_line
			(start 0.12065 -0.3048)
			(end 0.67945 -0.3048)
			(stroke
				(width 0.1)
				(type default)
			)
			(layer "F.Fab")
		)
		(fp_line
			(start 0.12065 -0.2794)
			(end 0.12065 -0.3048)
			(stroke
				(width 0.1)
				(type default)
			)
			(layer "F.Fab")
		)
		(fp_line
			(start 0.67945 -0.3048)
			(end 0.67945 0.3048)
			(stroke
				(width 0.1)
				(type default)
			)
			(layer "F.Fab")
		)
		(fp_line
			(start 0.67945 0.3048)
			(end 0.120396 0.3048)
			(stroke
				(width 0.1)
				(type default)
			)
			(layer "F.Fab")
		)
		(pad "1" smd circle
			(at -0.40005 0)
			(size 0 0)
			(layers "F.Cu" "F.Mask" "F.Paste")
			(net "P1V8_PCH_AUX")
		)
		(pad "2" smd circle
			(at 0.40005 0)
			(size 0 0)
			(layers "F.Cu" "F.Mask" "F.Paste")
			(net "SMB_M2_P0_1V8AUX_SDA_R")
		)
	)
	(footprint ""
		(layer "F.Cu")
		(at 385.716272 -65.688464)
		(property "Reference" "R762"
			(at 0 0 0)
			(layer "F.SilkS")
			(hide yes)
			(effects
				(font
					(size 1.27 1.27)
				)
			)
		)
		(property "Value" ""
			(at 0 0 0)
			(layer "F.Fab")
			(effects
				(font
					(size 1.27 1.27)
				)
			)
		)
		(duplicate_pad_numbers_are_jumpers no)
		(fp_line
			(start -0.7874 -0.4064)
			(end 0.7874 -0.4064)
			(stroke
				(width 0.1524)
				(type default)
			)
			(layer "F.SilkS")
		)
		(fp_line
			(start -0.7874 0.4064)
			(end -0.7874 -0.4064)
			(stroke
				(width 0.1524)
				(type default)
			)
			(layer "F.SilkS")
		)
		(fp_line
			(start 0.7874 -0.4064)
			(end 0.7874 0.4064)
			(stroke
				(width 0.1524)
				(type default)
			)
			(layer "F.SilkS")
		)
		(fp_line
			(start 0.7874 0.4064)
			(end -0.7874 0.4064)
			(stroke
				(width 0.1524)
				(type default)
			)
			(layer "F.SilkS")
		)
		(fp_line
			(start -0.67945 -0.305054)
			(end -0.12065 -0.305054)
			(stroke
				(width 0.1)
				(type default)
			)
			(layer "F.Fab")
		)
		(fp_line
			(start -0.67945 0.3048)
			(end -0.67945 -0.305054)
			(stroke
				(width 0.1)
				(type default)
			)
			(layer "F.Fab")
		)
		(fp_line
			(start -0.12065 -0.305054)
			(end -0.12065 -0.2794)
			(stroke
				(width 0.1)
				(type default)
			)
			(layer "F.Fab")
		)
		(fp_line
			(start -0.12065 -0.2794)
			(end 0.12065 -0.2794)
			(stroke
				(width 0.1)
				(type default)
			)
			(layer "F.Fab")
		)
		(fp_line
			(start -0.12065 0.2794)
			(end -0.12065 0.3048)
			(stroke
				(width 0.1)
				(type default)
			)
			(layer "F.Fab")
		)
		(fp_line
			(start -0.12065 0.3048)
			(end -0.67945 0.3048)
			(stroke
				(width 0.1)
				(type default)
			)
			(layer "F.Fab")
		)
		(fp_line
			(start 0.120396 0.2794)
			(end -0.12065 0.2794)
			(stroke
				(width 0.1)
				(type default)
			)
			(layer "F.Fab")
		)
		(fp_line
			(start 0.120396 0.3048)
			(end 0.120396 0.2794)
			(stroke
				(width 0.1)
				(type default)
			)
			(layer "F.Fab")
		)
		(fp_line
			(start 0.12065 -0.3048)
			(end 0.67945 -0.3048)
			(stroke
				(width 0.1)
				(type default)
			)
			(layer "F.Fab")
		)
		(fp_line
			(start 0.12065 -0.2794)
			(end 0.12065 -0.3048)
			(stroke
				(width 0.1)
				(type default)
			)
			(layer "F.Fab")
		)
		(fp_line
			(start 0.67945 -0.3048)
			(end 0.67945 0.3048)
			(stroke
				(width 0.1)
				(type default)
			)
			(layer "F.Fab")
		)
		(fp_line
			(start 0.67945 0.3048)
			(end 0.120396 0.3048)
			(stroke
				(width 0.1)
				(type default)
			)
			(layer "F.Fab")
		)
		(pad "1" smd circle
			(at -0.40005 0)
			(size 0 0)
			(layers "F.Cu" "F.Mask" "F.Paste")
			(net "JTAG_DBP_CPU_GTL_TCK")
		)
		(pad "2" smd circle
			(at 0.40005 0)
			(size 0 0)
			(layers "F.Cu" "F.Mask" "F.Paste")
			(net "JTAG_DBP_CPU_GTL_TCK_R")
		)
	)
	(footprint ""
		(layer "F.Cu")
		(at 81.915 -353.52482)
		(property "Reference" "H47"
			(at -3.58394 -5.029708 0)
			(unlocked yes)
			(layer "F.SilkS")
			(effects
				(font
					(size 0.7874 0.5842)
					(thickness 0.1524)
				)
				(justify left)
			)
		)
		(property "Value" ""
			(at 0 0 0)
			(layer "F.Fab")
			(effects
				(font
					(size 1.27 1.27)
				)
			)
		)
		(duplicate_pad_numbers_are_jumpers no)
		(pad "1" thru_hole circle
			(at 0 0)
			(size 8.001 8.001)
			(drill 3.2004)
			(layers "*.Cu" "*.Mask")
			(remove_unused_layers no)
			(net "GND")
			(clearance -2.1463)
			(padstack
				(mode front_inner_back)
				(layer "Inner"
					(shape circle)
					(size 5.0038 5.0038)
					(clearance -0.6477)
				)
				(layer "B.Cu"
					(shape circle)
					(size 8.001 8.001)
					(clearance -2.1463)
				)
			)
		)
	)
)
